# SCM (Grand Teton) — schematic netlist excerpt (pin names and nets, part order shuffled) for the footprints in the layout excerpt that follows; sources: Cadence DE-HDL packaged netlist, KiCad conversion of 12092022_DA0F0TMDCD0_F0T_Management_Board_D_brd_V3_OCP.brd

R847  Q_RES  0 5% CHIP  pkg 0402LF  page 10 : A = PCH_BEEP_LED ; B = FM_PCH_BEEP_LED
R586  Q_RES  4.7K 1% CHIP  pkg 0402LF  page 42 : A = P3V3_AUX ; B = BMC_CPLD_GPIO_2

(kicad_pcb
	(version 20260206)
	(generator "pcbnew")
	(generator_version "10.0")
	(general
		(thickness 1.6)
		(legacy_teardrops no)
	)
	(paper "A4")
	(title_block
		(title "12092022_DA0F0TMDCD0_F0T_Management_Board_D_brd_V3_OCP.brd")
		(comment 1 "Grand Teton / footprints 974-975 of 1440")
	)
	(layers
		(0 "F.Cu" signal "TOP")
		(4 "In1.Cu" signal "GND")
		(6 "In2.Cu" signal "IN1")
		(8 "In3.Cu" signal "GND1")
		(10 "In4.Cu" signal "IN2")
		(12 "In5.Cu" signal "VCC")
		(14 "In6.Cu" signal "VCC1")
		(16 "In7.Cu" signal "IN3")
		(18 "In8.Cu" signal "GND2")
		(20 "In9.Cu" signal "IN4")
		(22 "In10.Cu" signal "GND3")
		(2 "B.Cu" signal "BOTTOM")
		(9 "F.Adhes" user "F.Adhesive")
		(11 "B.Adhes" user "B.Adhesive")
		(13 "F.Paste" user "Package Geometry/Pastemask Top")
		(15 "B.Paste" user "Package Geometry/Pastemask Bottom")
		(5 "F.SilkS" user "Ref Des/Silkscreen Top")
		(7 "B.SilkS" user "Ref Des/Silkscreen Bottom")
		(1 "F.Mask" user "Board Geometry/Soldermask Top")
		(3 "B.Mask" user "Board Geometry/Soldermask Bottom")
		(17 "Dwgs.User" user "User.Drawings")
		(19 "Cmts.User" user "User.Comments")
		(21 "Eco1.User" user "User.Eco1")
		(23 "Eco2.User" user "User.Eco2")
		(25 "Edge.Cuts" user "Board Geometry/Outline")
		(27 "Margin" user)
		(31 "F.CrtYd" user "Package Geometry/Place Bound Top")
		(29 "B.CrtYd" user "Package Geometry/Place Bound Bottom")
		(35 "F.Fab" user "Ref Des/Assembly Top")
		(33 "B.Fab" user "Ref Des/Assembly Bottom")
	)
	(footprint ""
		(layer "B.Cu")
		(at 11.2776 -106.3752 -90)
		(property "Reference" "R847"
			(at 0 0 90)
			(layer "B.SilkS")
			(hide yes)
			(effects
				(font
					(size 1.27 1.27)
				)
				(justify mirror)
			)
		)
		(property "Value" ""
			(at 0 0 90)
			(layer "B.Fab")
			(effects
				(font
					(size 1.27 1.27)
				)
				(justify mirror)
			)
		)
		(duplicate_pad_numbers_are_jumpers no)
		(fp_line
			(start -0.7874 0.4064)
			(end 0.7874 0.4064)
			(stroke
				(width 0.1524)
				(type default)
			)
			(layer "B.SilkS")
		)
		(fp_line
			(start 0.7874 0.4064)
			(end 0.7874 -0.4064)
			(stroke
				(width 0.1524)
				(type default)
			)
			(layer "B.SilkS")
		)
		(fp_line
			(start -0.7874 -0.4064)
			(end -0.7874 0.4064)
			(stroke
				(width 0.1524)
				(type default)
			)
			(layer "B.SilkS")
		)
		(fp_line
			(start 0.7874 -0.4064)
			(end -0.7874 -0.4064)
			(stroke
				(width 0.1524)
				(type default)
			)
			(layer "B.SilkS")
		)
		(fp_line
			(start -0.67945 0.3048)
			(end -0.120396 0.3048)
			(stroke
				(width 0.1)
				(type default)
			)
			(layer "B.Fab")
		)
		(fp_line
			(start -0.120396 0.3048)
			(end -0.120396 0.2794)
			(stroke
				(width 0.1)
				(type default)
			)
			(layer "B.Fab")
		)
		(fp_line
			(start 0.12065 0.3048)
			(end 0.67945 0.3048)
			(stroke
				(width 0.1)
				(type default)
			)
			(layer "B.Fab")
		)
		(fp_line
			(start 0.67945 0.3048)
			(end 0.67945 -0.305054)
			(stroke
				(width 0.1)
				(type default)
			)
			(layer "B.Fab")
		)
		(fp_line
			(start -0.120396 0.2794)
			(end 0.12065 0.2794)
			(stroke
				(width 0.1)
				(type default)
			)
			(layer "B.Fab")
		)
		(fp_line
			(start 0.12065 0.2794)
			(end 0.12065 0.3048)
			(stroke
				(width 0.1)
				(type default)
			)
			(layer "B.Fab")
		)
		(fp_line
			(start -0.12065 -0.2794)
			(end -0.12065 -0.3048)
			(stroke
				(width 0.1)
				(type default)
			)
			(layer "B.Fab")
		)
		(fp_line
			(start 0.12065 -0.2794)
			(end -0.12065 -0.2794)
			(stroke
				(width 0.1)
				(type default)
			)
			(layer "B.Fab")
		)
		(fp_line
			(start -0.67945 -0.3048)
			(end -0.67945 0.3048)
			(stroke
				(width 0.1)
				(type default)
			)
			(layer "B.Fab")
		)
		(fp_line
			(start -0.12065 -0.3048)
			(end -0.67945 -0.3048)
			(stroke
				(width 0.1)
				(type default)
			)
			(layer "B.Fab")
		)
		(fp_line
			(start 0.12065 -0.305054)
			(end 0.12065 -0.2794)
			(stroke
				(width 0.1)
				(type default)
			)
			(layer "B.Fab")
		)
		(fp_line
			(start 0.67945 -0.305054)
			(end 0.12065 -0.305054)
			(stroke
				(width 0.1)
				(type default)
			)
			(layer "B.Fab")
		)
		(pad "1" smd circle
			(at 0.40005 0 90)
			(size 0 0)
			(layers "B.Cu" "B.Mask" "B.Paste")
			(net "PCH_BEEP_LED")
		)
		(pad "2" smd circle
			(at -0.40005 0 90)
			(size 0 0)
			(layers "B.Cu" "B.Mask" "B.Paste")
			(net "FM_PCH_BEEP_LED")
		)
	)
	(footprint ""
		(layer "B.Cu")
		(at 29.464 -91.059 180)
		(property "Reference" "R586"
			(at 0 0 0)
			(layer "B.SilkS")
			(hide yes)
			(effects
				(font
					(size 1.27 1.27)
				)
				(justify mirror)
			)
		)
		(property "Value" ""
			(at 0 0 0)
			(layer "B.Fab")
			(effects
				(font
					(size 1.27 1.27)
				)
				(justify mirror)
			)
		)
		(duplicate_pad_numbers_are_jumpers no)
		(fp_line
			(start 0.7874 0.4064)
			(end 0.7874 -0.4064)
			(stroke
				(width 0.1524)
				(type default)
			)
			(layer "B.SilkS")
		)
		(fp_line
			(start 0.7874 -0.4064)
			(end -0.7874 -0.4064)
			(stroke
				(width 0.1524)
				(type default)
			)
			(layer "B.SilkS")
		)
		(fp_line
			(start -0.7874 0.4064)
			(end 0.7874 0.4064)
			(stroke
				(width 0.1524)
				(type default)
			)
			(layer "B.SilkS")
		)
		(fp_line
			(start -0.7874 -0.4064)
			(end -0.7874 0.4064)
			(stroke
				(width 0.1524)
				(type default)
			)
			(layer "B.SilkS")
		)
		(fp_line
			(start 0.67945 0.3048)
			(end 0.67945 -0.305054)
			(stroke
				(width 0.1)
				(type default)
			)
			(layer "B.Fab")
		)
		(fp_line
			(start 0.67945 -0.305054)
			(end 0.12065 -0.305054)
			(stroke
				(width 0.1)
				(type default)
			)
			(layer "B.Fab")
		)
		(fp_line
			(start 0.12065 0.3048)
			(end 0.67945 0.3048)
			(stroke
				(width 0.1)
				(type default)
			)
			(layer "B.Fab")
		)
		(fp_line
			(start 0.12065 0.2794)
			(end 0.12065 0.3048)
			(stroke
				(width 0.1)
				(type default)
			)
			(layer "B.Fab")
		)
		(fp_line
			(start 0.12065 -0.2794)
			(end -0.12065 -0.2794)
			(stroke
				(width 0.1)
				(type default)
			)
			(layer "B.Fab")
		)
		(fp_line
			(start 0.12065 -0.305054)
			(end 0.12065 -0.2794)
			(stroke
				(width 0.1)
				(type default)
			)
			(layer "B.Fab")
		)
		(fp_line
			(start -0.120396 0.3048)
			(end -0.120396 0.2794)
			(stroke
				(width 0.1)
				(type default)
			)
			(layer "B.Fab")
		)
		(fp_line
			(start -0.120396 0.2794)
			(end 0.12065 0.2794)
			(stroke
				(width 0.1)
				(type default)
			)
			(layer "B.Fab")
		)
		(fp_line
			(start -0.12065 -0.2794)
			(end -0.12065 -0.3048)
			(stroke
				(width 0.1)
				(type default)
			)
			(layer "B.Fab")
		)
		(fp_line
			(start -0.12065 -0.3048)
			(end -0.67945 -0.3048)
			(stroke
				(width 0.1)
				(type default)
			)
			(layer "B.Fab")
		)
		(fp_line
			(start -0.67945 0.3048)
			(end -0.120396 0.3048)
			(stroke
				(width 0.1)
				(type default)
			)
			(layer "B.Fab")
		)
		(fp_line
			(start -0.67945 -0.3048)
			(end -0.67945 0.3048)
			(stroke
				(width 0.1)
				(type default)
			)
			(layer "B.Fab")
		)
		(pad "1" smd circle
			(at 0.40005 0)
			(size 0 0)
			(layers "B.Cu" "B.Mask" "B.Paste")
			(net "P3V3_AUX")
		)
		(pad "2" smd circle
			(at -0.40005 0)
			(size 0 0)
			(layers "B.Cu" "B.Mask" "B.Paste")
			(net "BMC_CPLD_GPIO_2")
		)
	)
)
